(kicad_pcb
	(version 20260206)
	(generator "pcbnew")
	(generator_version "10.0")
	(general
		(thickness 1.6)
		(legacy_teardrops no)
	)
	(paper "A4")
	(title_block
		(title "Bryce Canyon_F.DPB_16315-1-OCP.brd")
		(comment 1 "Bryce Canyon / footprints 1224-1231 of 2223")
	)
	(layers
		(0 "F.Cu" signal "TOP")
		(4 "In1.Cu" signal "L2GND")
		(6 "In2.Cu" signal "L3")
		(8 "In3.Cu" signal "L4GND")
		(10 "In4.Cu" signal "L5")
		(12 "In5.Cu" signal "L6VCC")
		(14 "In6.Cu" signal "L7VCC")
		(16 "In7.Cu" signal "L8")
		(18 "In8.Cu" signal "L9GND")
		(20 "In9.Cu" signal "L10")
		(22 "In10.Cu" signal "L11GND")
		(2 "B.Cu" signal "BOTTOM")
		(9 "F.Adhes" user "F.Adhesive")
		(11 "B.Adhes" user "B.Adhesive")
		(13 "F.Paste" user "Package Geometry/Pastemask Top")
		(15 "B.Paste" user "Package Geometry/Pastemask Bottom")
		(5 "F.SilkS" user "Ref Des/Silkscreen Top")
		(7 "B.SilkS" user "Ref Des/Silkscreen Bottom")
		(1 "F.Mask" user "Board Geometry/Soldermask Top")
		(3 "B.Mask" user "Board Geometry/Soldermask Bottom")
		(17 "Dwgs.User" user "User.Drawings")
		(19 "Cmts.User" user "User.Comments")
		(21 "Eco1.User" user "User.Eco1")
		(23 "Eco2.User" user "User.Eco2")
		(25 "Edge.Cuts" user "Board Geometry/Outline")
		(27 "Margin" user)
		(31 "F.CrtYd" user "Package Geometry/Place Bound Top")
		(29 "B.CrtYd" user "Package Geometry/Place Bound Bottom")
		(35 "F.Fab" user "Ref Des/Assembly Top")
		(33 "B.Fab" user "Ref Des/Assembly Bottom")
	)
	(footprint ""
		(layer "F.Cu")
		(at 141.042898 -53.507894 -90)
		(property "Reference" "R789"
			(at 0 0 270)
			(layer "F.SilkS")
			(hide yes)
			(effects
				(font
					(size 1.27 1.27)
				)
			)
		)
		(property "Value" "300KR2F-GP"
			(at 0.064008 -3.993896 270)
			(unlocked yes)
			(layer "F.Fab")
			(hide yes)
			(effects
				(font
					(size 1.016 1.016)
					(thickness 0.1524)
				)
			)
		)
		(property "Device Type" "R402H16"
			(at 0.064008 -5.517896 270)
			(unlocked yes)
			(layer "F.Fab")
			(hide yes)
			(effects
				(font
					(size 1.016 1.016)
					(thickness 0.1524)
				)
			)
		)
		(duplicate_pad_numbers_are_jumpers no)
		(fp_line
			(start -0.508 -0.9398)
			(end -0.508 0.9398)
			(stroke
				(width 0.1524)
				(type default)
			)
			(layer "F.SilkS")
		)
		(fp_line
			(start 0.508 -0.9398)
			(end -0.508 -0.9398)
			(stroke
				(width 0.1524)
				(type default)
			)
			(layer "F.SilkS")
		)
		(fp_rect
			(start -0.508 0.9398)
			(end 0.508 -0.9398)
			(stroke
				(width 0)
				(type default)
			)
			(fill no)
			(layer "F.CrtYd")
		)
		(fp_rect
			(start -0.508 0.9398)
			(end 0.508 -0.9398)
			(stroke
				(width 0)
				(type default)
			)
			(fill no)
			(layer "F.Fab")
		)
		(pad "1" smd custom
			(at 0 -0.4445 270)
			(size 0.1397 0.1397)
			(layers "F.Cu" "F.Mask" "F.Paste")
			(net "SW_HDD_N28")
			(options
				(clearance outline)
				(anchor circle)
			)
			(primitives
				(gr_poly
					(pts
						(arc
							(start -0.1778 -0.2794)
							(mid -0.249642 -0.249642)
							(end -0.2794 -0.1778)
						)
						(arc
							(start -0.2794 0.1778)
							(mid -0.249642 0.249642)
							(end -0.1778 0.2794)
						)
						(arc
							(start 0.1778 0.2794)
							(mid 0.249642 0.249642)
							(end 0.2794 0.1778)
						)
						(arc
							(start 0.2794 -0.1778)
							(mid 0.249642 -0.249642)
							(end 0.1778 -0.2794)
						)
					)
					(width 0)
					(fill yes)
				)
			)
		)
		(pad "2" smd custom
			(at 0 0.4445 270)
			(size 0.1397 0.1397)
			(layers "F.Cu" "F.Mask" "F.Paste")
			(net "P12V_A")
			(options
				(clearance outline)
				(anchor circle)
			)
			(primitives
				(gr_poly
					(pts
						(arc
							(start -0.1778 -0.2794)
							(mid -0.249642 -0.249642)
							(end -0.2794 -0.1778)
						)
						(arc
							(start -0.2794 0.1778)
							(mid -0.249642 0.249642)
							(end -0.1778 0.2794)
						)
						(arc
							(start 0.1778 0.2794)
							(mid 0.249642 0.249642)
							(end 0.2794 0.1778)
						)
						(arc
							(start 0.2794 -0.1778)
							(mid 0.249642 -0.249642)
							(end 0.1778 -0.2794)
						)
					)
					(width 0)
					(fill yes)
				)
			)
		)
	)
	(footprint ""
		(layer "F.Cu")
		(at 461.0989 -52.872894 -90)
		(property "Reference" "Q203"
			(at 0 0 270)
			(layer "F.SilkS")
			(hide yes)
			(effects
				(font
					(size 1.27 1.27)
				)
			)
		)
		(property "Value" "AO4406AL-GP"
			(at -3.707384 -1.5367 270)
			(unlocked yes)
			(layer "F.Fab")
			(hide yes)
			(effects
				(font
					(size 1.016 1.016)
					(thickness 0.1524)
				)
			)
		)
		(property "Device Type" "SOIC8H69"
			(at -3.707384 -3.0607 270)
			(unlocked yes)
			(layer "F.Fab")
			(hide yes)
			(effects
				(font
					(size 1.016 1.016)
					(thickness 0.1524)
				)
			)
		)
		(duplicate_pad_numbers_are_jumpers no)
		(fp_line
			(start -2.6289 3.4417)
			(end -2.6289 1.4732)
			(stroke
				(width 0.381)
				(type default)
			)
			(layer "F.SilkS")
		)
		(fp_line
			(start -2.7432 1.4224)
			(end -2.6416 1.4224)
			(stroke
				(width 0.1524)
				(type default)
			)
			(layer "F.SilkS")
		)
		(fp_line
			(start -2.7432 1.4224)
			(end 2.1336 1.4224)
			(stroke
				(width 0.1524)
				(type default)
			)
			(layer "F.SilkS")
		)
		(fp_line
			(start 2.1336 1.4224)
			(end 2.1336 -1.4224)
			(stroke
				(width 0.1524)
				(type default)
			)
			(layer "F.SilkS")
		)
		(fp_line
			(start -2.1844 -0.0508)
			(end -2.7178 0.508)
			(stroke
				(width 0.1524)
				(type default)
			)
			(layer "F.SilkS")
		)
		(fp_line
			(start -2.7178 -0.508)
			(end -2.1844 -0.0508)
			(stroke
				(width 0.1524)
				(type default)
			)
			(layer "F.SilkS")
		)
		(fp_line
			(start -2.7432 -1.4224)
			(end -2.7432 1.4224)
			(stroke
				(width 0.1524)
				(type default)
			)
			(layer "F.SilkS")
		)
		(fp_line
			(start 2.1336 -1.4224)
			(end -2.7432 -1.4224)
			(stroke
				(width 0.1524)
				(type default)
			)
			(layer "F.SilkS")
		)
		(fp_poly
			(pts
				(xy -2.2098 -1.4224) (xy -2.2098 1.4224) (xy 2.2098 1.4224) (xy 2.2098 -1.4224)
			)
			(stroke
				(width 0)
				(type default)
			)
			(fill yes)
			(layer "F.SilkS")
		)
		(fp_rect
			(start -2.450084 2.999994)
			(end 2.450084 -2.999994)
			(stroke
				(width 0)
				(type default)
			)
			(fill no)
			(layer "F.CrtYd")
		)
		(fp_poly
			(pts
				(xy -2.8194 3.6322) (xy -2.8194 -3.6322) (xy 2.8194 -3.6322) (xy 2.8194 1.18364) (xy 2.450084 1.18364)
				(xy 2.450084 -2.999994) (xy -2.450084 -2.999994) (xy -2.450084 2.999994) (xy 2.450084 2.999994)
				(xy 2.450084 1.18618) (xy 2.8194 1.18618) (xy 2.8194 3.6322)
			)
			(stroke
				(width 0)
				(type default)
			)
			(fill no)
			(layer "F.CrtYd")
		)
		(fp_rect
			(start -2.8194 3.6322)
			(end 2.8194 -3.6322)
			(stroke
				(width 0)
				(type default)
			)
			(fill no)
			(layer "F.Fab")
		)
		(pad "1" smd rect
			(at -1.905 2.54 270)
			(size 0.635 1.651)
			(layers "F.Cu" "F.Mask" "F.Paste")
			(net "P5V_HDD34")
		)
		(pad "2" smd rect
			(at -0.635 2.54 270)
			(size 0.635 1.651)
			(layers "F.Cu" "F.Mask" "F.Paste")
			(net "P5V_HDD34")
		)
		(pad "3" smd rect
			(at 0.635 2.54 270)
			(size 0.635 1.651)
			(layers "F.Cu" "F.Mask" "F.Paste")
			(net "P5V_HDD34")
		)
		(pad "4" smd rect
			(at 1.905 2.54 270)
			(size 0.635 1.651)
			(layers "F.Cu" "F.Mask" "F.Paste")
			(net "SW_HDD_P34")
		)
		(pad "5" smd rect
			(at 1.905 -2.54 270)
			(size 0.635 1.651)
			(layers "F.Cu" "F.Mask" "F.Paste")
			(net "P5V_A_4")
		)
		(pad "6" smd rect
			(at 0.635 -2.54 270)
			(size 0.635 1.651)
			(layers "F.Cu" "F.Mask" "F.Paste")
			(net "P5V_A_4")
		)
		(pad "7" smd rect
			(at -0.635 -2.54 270)
			(size 0.635 1.651)
			(layers "F.Cu" "F.Mask" "F.Paste")
			(net "P5V_A_4")
		)
		(pad "8" smd rect
			(at -1.905 -2.54 270)
			(size 0.635 1.651)
			(layers "F.Cu" "F.Mask" "F.Paste")
			(net "P5V_A_4")
		)
	)
	(footprint ""
		(layer "F.Cu")
		(at 459.7019 -73.954894 180)
		(property "Reference" "C488"
			(at 0 0 180)
			(layer "F.SilkS")
			(hide yes)
			(effects
				(font
					(size 1.27 1.27)
				)
			)
		)
		(property "Value" "SC4D7U25V5KX-1-GP"
			(at -0.0762 -6.1214 180)
			(unlocked yes)
			(layer "F.Fab")
			(hide yes)
			(effects
				(font
					(size 1.016 1.016)
					(thickness 0.1524)
				)
			)
		)
		(property "Device Type" "C805H58"
			(at -0.0762 -8.1534 180)
			(unlocked yes)
			(layer "F.Fab")
			(hide yes)
			(effects
				(font
					(size 1.016 1.016)
					(thickness 0.1524)
				)
			)
		)
		(duplicate_pad_numbers_are_jumpers no)
		(fp_line
			(start 0.635 0)
			(end -0.635 0)
			(stroke
				(width 0.508)
				(type default)
			)
			(layer "F.SilkS")
		)
		(fp_rect
			(start -0.9652 1.778)
			(end 0.9652 -1.778)
			(stroke
				(width 0)
				(type default)
			)
			(fill no)
			(layer "F.CrtYd")
		)
		(fp_poly
			(pts
				(xy -0.9652 -1.778) (xy 0.9652 -1.778) (xy 0.9652 1.778) (xy -0.9652 1.778)
			)
			(stroke
				(width 0)
				(type default)
			)
			(fill no)
			(layer "F.Fab")
		)
		(pad "1" smd rect
			(at 0 -0.9652 180)
			(size 1.397 1.143)
			(layers "F.Cu" "F.Mask" "F.Paste")
			(net "P12V_HDD34")
		)
		(pad "2" smd rect
			(at 0 0.9652 180)
			(size 1.397 1.143)
			(layers "F.Cu" "F.Mask" "F.Paste")
			(net "GND")
		)
	)
	(footprint ""
		(layer "F.Cu")
		(at 272.542 -332.50505 180)
		(property "Reference" "VIA51"
			(at 0 0 180)
			(layer "F.SilkS")
			(hide yes)
			(effects
				(font
					(size 1.27 1.27)
				)
			)
		)
		(property "Value" "100OHM-8L-1D6MM-L18L16-GP"
			(at -3.7211 -4.5085 180)
			(unlocked yes)
			(layer "F.Fab")
			(hide yes)
			(effects
				(font
					(size 1.016 1.016)
					(thickness 0.1524)
				)
			)
		)
		(property "Device Type" "VIA-PCIE-4P-394076"
			(at -3.7211 -6.0325 180)
			(unlocked yes)
			(layer "F.Fab")
			(hide yes)
			(effects
				(font
					(size 1.016 1.016)
					(thickness 0.1524)
				)
			)
		)
		(duplicate_pad_numbers_are_jumpers no)
		(fp_rect
			(start -1.9685 0.381)
			(end 1.9685 -0.381)
			(stroke
				(width 0)
				(type default)
			)
			(fill no)
			(layer "F.CrtYd")
		)
		(fp_rect
			(start -1.9685 0.381)
			(end 1.9685 -0.381)
			(stroke
				(width 0)
				(type default)
			)
			(fill no)
			(layer "F.Fab")
		)
		(pad "1" thru_hole circle
			(at -1.5875 0 180)
			(size 0.508 0.508)
			(drill 0.254)
			(layers "*.Cu" "*.Mask")
			(remove_unused_layers no)
			(net "GND")
			(clearance 0.127)
			(thermal_gap 0.127)
		)
		(pad "2" thru_hole circle
			(at -0.5715 0 180)
			(size 0.508 0.508)
			(drill 0.254)
			(layers "*.Cu" "*.Mask")
			(remove_unused_layers no)
			(net "PHY_SCC_A_TO_DRV_A_15_DP")
			(clearance 0.127)
			(thermal_gap 0.127)
		)
		(pad "3" thru_hole circle
			(at 0.5715 0 180)
			(size 0.508 0.508)
			(drill 0.254)
			(layers "*.Cu" "*.Mask")
			(remove_unused_layers no)
			(net "PHY_SCC_A_TO_DRV_A_15_DN")
			(clearance 0.127)
			(thermal_gap 0.127)
		)
		(pad "4" thru_hole circle
			(at 1.5875 0 180)
			(size 0.508 0.508)
			(drill 0.254)
			(layers "*.Cu" "*.Mask")
			(remove_unused_layers no)
			(net "GND")
			(clearance 0.127)
			(thermal_gap 0.127)
		)
	)
	(footprint ""
		(layer "F.Cu")
		(at 463.5119 -162.792918 90)
		(property "Reference" "D22"
			(at 0 0 90)
			(layer "F.SilkS")
			(hide yes)
			(effects
				(font
					(size 1.27 1.27)
				)
			)
		)
		(property "Value" "RB551V30-GP"
			(at 0 -6.7818 90)
			(unlocked yes)
			(layer "F.Fab")
			(hide yes)
			(effects
				(font
					(size 1.016 1.016)
					(thickness 0.1524)
				)
			)
		)
		(property "Device Type" "SOD323AKH38"
			(at 0 -8.6868 90)
			(unlocked yes)
			(layer "F.Fab")
			(hide yes)
			(effects
				(font
					(size 1.016 1.016)
					(thickness 0.1524)
				)
			)
		)
		(duplicate_pad_numbers_are_jumpers no)
		(fp_line
			(start 0.889 -1.9304)
			(end 0.889 2.159)
			(stroke
				(width 0.1524)
				(type default)
			)
			(layer "F.SilkS")
		)
		(fp_line
			(start -0.889 -1.9304)
			(end 0.889 -1.9304)
			(stroke
				(width 0.1524)
				(type default)
			)
			(layer "F.SilkS")
		)
		(fp_line
			(start 0.762 2.0574)
			(end -0.762 2.0574)
			(stroke
				(width 0.508)
				(type default)
			)
			(layer "F.SilkS")
		)
		(fp_line
			(start 0.889 2.159)
			(end -0.889 2.159)
			(stroke
				(width 0.1524)
				(type default)
			)
			(layer "F.SilkS")
		)
		(fp_line
			(start -0.889 2.159)
			(end -0.889 -1.9304)
			(stroke
				(width 0.1524)
				(type default)
			)
			(layer "F.SilkS")
		)
		(fp_rect
			(start -1.016 2.3114)
			(end 1.016 -2.0066)
			(stroke
				(width 0)
				(type default)
			)
			(fill no)
			(layer "F.CrtYd")
		)
		(fp_poly
			(pts
				(xy -1.016 -2.0066) (xy 1.016 -2.0066) (xy 1.016 2.3114) (xy -1.016 2.3114)
			)
			(stroke
				(width 0)
				(type default)
			)
			(fill no)
			(layer "F.Fab")
		)
		(pad "A" smd rect
			(at 0 -1.143 90)
			(size 0.5588 1.016)
			(layers "F.Cu" "F.Mask" "F.Paste")
			(net "SW_HDD_R22")
		)
		(pad "K" smd rect
			(at 0 1.143 90)
			(size 0.5588 1.016)
			(layers "F.Cu" "F.Mask" "F.Paste")
			(net "SW_HDD_N22")
		)
	)
	(footprint ""
		(layer "F.Cu")
		(at 479.036126 -186.287918)
		(property "Reference" "C343"
			(at 0 0 0)
			(layer "F.SilkS")
			(hide yes)
			(effects
				(font
					(size 1.27 1.27)
				)
			)
		)
		(property "Value" "SC4D7U25V5KX-1-GP"
			(at -0.0762 -6.1214 0)
			(unlocked yes)
			(layer "F.Fab")
			(hide yes)
			(effects
				(font
					(size 1.016 1.016)
					(thickness 0.1524)
				)
			)
		)
		(property "Device Type" "C805H58"
			(at -0.0762 -8.1534 0)
			(unlocked yes)
			(layer "F.Fab")
			(hide yes)
			(effects
				(font
					(size 1.016 1.016)
					(thickness 0.1524)
				)
			)
		)
		(duplicate_pad_numbers_are_jumpers no)
		(fp_line
			(start 0.635 0)
			(end -0.635 0)
			(stroke
				(width 0.508)
				(type default)
			)
			(layer "F.SilkS")
		)
		(fp_rect
			(start -0.9652 1.778)
			(end 0.9652 -1.778)
			(stroke
				(width 0)
				(type default)
			)
			(fill no)
			(layer "F.CrtYd")
		)
		(fp_poly
			(pts
				(xy -0.9652 -1.778) (xy 0.9652 -1.778) (xy 0.9652 1.778) (xy -0.9652 1.778)
			)
			(stroke
				(width 0)
				(type default)
			)
			(fill no)
			(layer "F.Fab")
		)
		(pad "1" smd rect
			(at 0 -0.9652)
			(size 1.397 1.143)
			(layers "F.Cu" "F.Mask" "F.Paste")
			(net "P12V_HDD23")
		)
		(pad "2" smd rect
			(at 0 0.9652)
			(size 1.397 1.143)
			(layers "F.Cu" "F.Mask" "F.Paste")
			(net "GND")
		)
	)
	(footprint ""
		(layer "F.Cu")
		(at 356.173278 -138.717274 180)
		(property "Reference" "R1101"
			(at 0 0 180)
			(layer "F.SilkS")
			(hide yes)
			(effects
				(font
					(size 1.27 1.27)
				)
			)
		)
		(property "Value" "10R5F-1-GP"
			(at 0 -8.9535 180)
			(unlocked yes)
			(layer "F.Fab")
			(hide yes)
			(effects
				(font
					(size 1.27 1.016)
					(thickness 0.1524)
				)
			)
		)
		(property "Device Type" "R805H24"
			(at 0 -10.6299 180)
			(unlocked yes)
			(layer "F.Fab")
			(hide yes)
			(effects
				(font
					(size 1.27 1.016)
					(thickness 0.1524)
				)
			)
		)
		(duplicate_pad_numbers_are_jumpers no)
		(fp_line
			(start 0.889 1.7018)
			(end 0.889 -0.508)
			(stroke
				(width 0.1524)
				(type default)
			)
			(layer "F.SilkS")
		)
		(fp_line
			(start 0.889 -1.7018)
			(end 0.889 -0.381)
			(stroke
				(width 0.1524)
				(type default)
			)
			(layer "F.SilkS")
		)
		(fp_line
			(start 0.889 -1.7018)
			(end -0.889 -1.7018)
			(stroke
				(width 0.1524)
				(type default)
			)
			(layer "F.SilkS")
		)
		(fp_line
			(start -0.889 1.7018)
			(end 0.889 1.7018)
			(stroke
				(width 0.1524)
				(type default)
			)
			(layer "F.SilkS")
		)
		(fp_line
			(start -0.889 0.0762)
			(end -0.889 1.7018)
			(stroke
				(width 0.1524)
				(type default)
			)
			(layer "F.SilkS")
		)
		(fp_line
			(start -0.889 -1.7018)
			(end -0.889 0.2794)
			(stroke
				(width 0.1524)
				(type default)
			)
			(layer "F.SilkS")
		)
		(fp_poly
			(pts
				(xy 0.9652 -1.778) (xy 0.9652 1.778) (xy -0.9652 1.778) (xy -0.9652 -1.778)
			)
			(stroke
				(width 0)
				(type default)
			)
			(fill no)
			(layer "F.CrtYd")
		)
		(fp_rect
			(start -0.9652 1.778)
			(end 0.9652 -1.778)
			(stroke
				(width 0)
				(type default)
			)
			(fill no)
			(layer "F.Fab")
		)
		(pad "1" smd rect
			(at 0 -0.9652 180)
			(size 1.397 1.143)
			(layers "F.Cu" "F.Mask" "F.Paste")
			(net "MB1_12V_CTRL_GATE1")
		)
		(pad "2" smd rect
			(at 0 0.9652 180)
			(size 1.397 1.143)
			(layers "F.Cu" "F.Mask" "F.Paste")
			(net "MB1_CM_GATE_R")
		)
	)
	(footprint ""
		(layer "F.Cu")
		(at 164.506402 -129.286)
		(property "Reference" "R311"
			(at 0 0 0)
			(layer "F.SilkS")
			(hide yes)
			(effects
				(font
					(size 1.27 1.27)
				)
			)
		)
		(property "Value" "130R3F-GP"
			(at -0.0254 -2.5146 0)
			(unlocked yes)
			(layer "F.Fab")
			(hide yes)
			(effects
				(font
					(size 1.016 1.016)
					(thickness 0.1524)
				)
			)
		)
		(property "Device Type" "R603H22"
			(at -0.0254 -4.0386 0)
			(unlocked yes)
			(layer "F.Fab")
			(hide yes)
			(effects
				(font
					(size 1.016 1.016)
					(thickness 0.1524)
				)
			)
		)
		(duplicate_pad_numbers_are_jumpers no)
		(fp_line
			(start -0.4826 0)
			(end -0.2032 0)
			(stroke
				(width 0.2032)
				(type default)
			)
			(layer "F.SilkS")
		)
		(fp_line
			(start 0.2032 0)
			(end 0.4826 0)
			(stroke
				(width 0.2032)
				(type default)
			)
			(layer "F.SilkS")
		)
		(fp_rect
			(start -0.5842 1.3335)
			(end 0.5842 -1.3335)
			(stroke
				(width 0)
				(type default)
			)
			(fill no)
			(layer "F.CrtYd")
		)
		(fp_rect
			(start -0.5842 1.3335)
			(end 0.5842 -1.3335)
			(stroke
				(width 0)
				(type default)
			)
			(fill no)
			(layer "F.Fab")
		)
		(pad "1" smd custom
			(at 0 -0.762)
			(size 0.2159 0.2159)
			(layers "F.Cu" "F.Mask" "F.Paste")
			(net "P5V_A_2")
			(options
				(clearance outline)
				(anchor circle)
			)
			(primitives
				(gr_poly
					(pts
						(arc
							(start -0.3302 -0.4318)
							(mid -0.402042 -0.402042)
							(end -0.4318 -0.3302)
						)
						(arc
							(start -0.4318 0.3302)
							(mid -0.402042 0.402042)
							(end -0.3302 0.4318)
						)
						(arc
							(start 0.3302 0.4318)
							(mid 0.402042 0.402042)
							(end 0.4318 0.3302)
						)
						(arc
							(start 0.4318 -0.3302)
							(mid 0.402042 -0.402042)
							(end 0.3302 -0.4318)
						)
					)
					(width 0)
					(fill yes)
				)
			)
		)
		(pad "2" smd custom
			(at 0 0.762)
			(size 0.2159 0.2159)
			(layers "F.Cu" "F.Mask" "F.Paste")
			(net "FLT_HDD17")
			(options
				(clearance outline)
				(anchor circle)
			)
			(primitives
				(gr_poly
					(pts
						(arc
							(start -0.3302 -0.4318)
							(mid -0.402042 -0.402042)
							(end -0.4318 -0.3302)
						)
						(arc
							(start -0.4318 0.3302)
							(mid -0.402042 0.402042)
							(end -0.3302 0.4318)
						)
						(arc
							(start 0.3302 0.4318)
							(mid 0.402042 0.402042)
							(end 0.4318 0.3302)
						)
						(arc
							(start 0.4318 -0.3302)
							(mid 0.402042 -0.402042)
							(end 0.3302 -0.4318)
						)
					)
					(width 0)
					(fill yes)
				)
			)
		)
	)
)
